(kicad_pcb
	(version 20260206)
	(generator "pcbnew")
	(generator_version "10.0")
	(general
		(thickness 1.6)
		(legacy_teardrops no)
	)
	(paper "A4")
	(title_block
		(title "01162023_DA0F0TEBIF0_F0T_Expander_BD_F_brd_V02_OCP.brd")
		(comment 1 "Grand Teton / footprints 4671-4677 of 9728")
	)
	(layers
		(0 "F.Cu" signal "TOP")
		(4 "In1.Cu" signal "GND")
		(6 "In2.Cu" signal "VCC")
		(8 "In3.Cu" signal "VCC1")
		(10 "In4.Cu" signal "GND1")
		(12 "In5.Cu" signal "IN1")
		(14 "In6.Cu" signal "GND2")
		(16 "In7.Cu" signal "IN2")
		(18 "In8.Cu" signal "GND3")
		(20 "In9.Cu" signal "IN3")
		(22 "In10.Cu" signal "GND4")
		(24 "In11.Cu" signal "IN4")
		(26 "In12.Cu" signal "GND5")
		(28 "In13.Cu" signal "IN5")
		(30 "In14.Cu" signal "GND6")
		(32 "In15.Cu" signal "IN6")
		(34 "In16.Cu" signal "GND7")
		(2 "B.Cu" signal "BOTTOM")
		(9 "F.Adhes" user "F.Adhesive")
		(11 "B.Adhes" user "B.Adhesive")
		(13 "F.Paste" user "Package Geometry/Pastemask Top")
		(15 "B.Paste" user "Package Geometry/Pastemask Bottom")
		(5 "F.SilkS" user "Ref Des/Silkscreen Top")
		(7 "B.SilkS" user "Ref Des/Silkscreen Bottom")
		(1 "F.Mask" user "Board Geometry/Soldermask Top")
		(3 "B.Mask" user "Board Geometry/Soldermask Bottom")
		(17 "Dwgs.User" user "User.Drawings")
		(19 "Cmts.User" user "User.Comments")
		(21 "Eco1.User" user "User.Eco1")
		(23 "Eco2.User" user "User.Eco2")
		(25 "Edge.Cuts" user "Board Geometry/Outline")
		(27 "Margin" user)
		(31 "F.CrtYd" user "Package Geometry/Place Bound Top")
		(29 "B.CrtYd" user "Package Geometry/Place Bound Bottom")
		(35 "F.Fab" user "Ref Des/Assembly Top")
		(33 "B.Fab" user "Ref Des/Assembly Bottom")
	)
	(footprint ""
		(layer "F.Cu")
		(at 392.9253 -343.952322 90)
		(property "Reference" "C756"
			(at 0 0 90)
			(layer "F.SilkS")
			(hide yes)
			(effects
				(font
					(size 1.27 1.27)
				)
			)
		)
		(property "Value" ""
			(at 0 0 90)
			(layer "F.Fab")
			(effects
				(font
					(size 1.27 1.27)
				)
			)
		)
		(duplicate_pad_numbers_are_jumpers no)
		(fp_line
			(start 0.299974 -0.150114)
			(end 0.299974 0.150114)
			(stroke
				(width 0.1)
				(type default)
			)
			(layer "F.Fab")
		)
		(fp_line
			(start -0.299974 -0.150114)
			(end 0.299974 -0.150114)
			(stroke
				(width 0.1)
				(type default)
			)
			(layer "F.Fab")
		)
		(fp_line
			(start 0.299974 0.150114)
			(end -0.299974 0.150114)
			(stroke
				(width 0.1)
				(type default)
			)
			(layer "F.Fab")
		)
		(fp_line
			(start -0.299974 0.150114)
			(end -0.299974 -0.150114)
			(stroke
				(width 0.1)
				(type default)
			)
			(layer "F.Fab")
		)
		(pad "1" smd rect
			(at -0.2667 0 90)
			(size 0.3048 0.381)
			(layers "F.Cu" "F.Mask" "F.Paste")
			(net "P5E_PEX3_STN5_TX_DP<82>")
		)
		(pad "2" smd rect
			(at 0.2667 0 90)
			(size 0.3048 0.381)
			(layers "F.Cu" "F.Mask" "F.Paste")
			(net "P5E_PEX3_STN5_TX_C_DP<82>")
		)
	)
	(footprint ""
		(layer "F.Cu")
		(at 361.188 -173.99 180)
		(property "Reference" "R4710"
			(at 0 0 180)
			(layer "F.SilkS")
			(hide yes)
			(effects
				(font
					(size 1.27 1.27)
				)
			)
		)
		(property "Value" ""
			(at 0 0 180)
			(layer "F.Fab")
			(effects
				(font
					(size 1.27 1.27)
				)
			)
		)
		(duplicate_pad_numbers_are_jumpers no)
		(fp_line
			(start 0.7874 0.4064)
			(end -0.7874 0.4064)
			(stroke
				(width 0.1524)
				(type default)
			)
			(layer "F.SilkS")
		)
		(fp_line
			(start 0.7874 -0.4064)
			(end 0.7874 0.4064)
			(stroke
				(width 0.1524)
				(type default)
			)
			(layer "F.SilkS")
		)
		(fp_line
			(start -0.7874 0.4064)
			(end -0.7874 -0.4064)
			(stroke
				(width 0.1524)
				(type default)
			)
			(layer "F.SilkS")
		)
		(fp_line
			(start -0.7874 -0.4064)
			(end 0.7874 -0.4064)
			(stroke
				(width 0.1524)
				(type default)
			)
			(layer "F.SilkS")
		)
		(fp_line
			(start 0.67945 0.3048)
			(end 0.120396 0.3048)
			(stroke
				(width 0.1)
				(type default)
			)
			(layer "F.Fab")
		)
		(fp_line
			(start 0.67945 -0.3048)
			(end 0.67945 0.3048)
			(stroke
				(width 0.1)
				(type default)
			)
			(layer "F.Fab")
		)
		(fp_line
			(start 0.12065 -0.2794)
			(end 0.12065 -0.3048)
			(stroke
				(width 0.1)
				(type default)
			)
			(layer "F.Fab")
		)
		(fp_line
			(start 0.12065 -0.3048)
			(end 0.67945 -0.3048)
			(stroke
				(width 0.1)
				(type default)
			)
			(layer "F.Fab")
		)
		(fp_line
			(start 0.120396 0.3048)
			(end 0.120396 0.2794)
			(stroke
				(width 0.1)
				(type default)
			)
			(layer "F.Fab")
		)
		(fp_line
			(start 0.120396 0.2794)
			(end -0.12065 0.2794)
			(stroke
				(width 0.1)
				(type default)
			)
			(layer "F.Fab")
		)
		(fp_line
			(start -0.12065 0.3048)
			(end -0.67945 0.3048)
			(stroke
				(width 0.1)
				(type default)
			)
			(layer "F.Fab")
		)
		(fp_line
			(start -0.12065 0.2794)
			(end -0.12065 0.3048)
			(stroke
				(width 0.1)
				(type default)
			)
			(layer "F.Fab")
		)
		(fp_line
			(start -0.12065 -0.2794)
			(end 0.12065 -0.2794)
			(stroke
				(width 0.1)
				(type default)
			)
			(layer "F.Fab")
		)
		(fp_line
			(start -0.12065 -0.305054)
			(end -0.12065 -0.2794)
			(stroke
				(width 0.1)
				(type default)
			)
			(layer "F.Fab")
		)
		(fp_line
			(start -0.67945 0.3048)
			(end -0.67945 -0.305054)
			(stroke
				(width 0.1)
				(type default)
			)
			(layer "F.Fab")
		)
		(fp_line
			(start -0.67945 -0.305054)
			(end -0.12065 -0.305054)
			(stroke
				(width 0.1)
				(type default)
			)
			(layer "F.Fab")
		)
		(pad "1" smd circle
			(at -0.40005 0 180)
			(size 0 0)
			(layers "F.Cu" "F.Mask" "F.Paste")
			(net "SSD7_PEX_PWR_EN")
		)
		(pad "2" smd circle
			(at 0.40005 0 180)
			(size 0 0)
			(layers "F.Cu" "F.Mask" "F.Paste")
			(net "SSD7_PEX_PWR_EN_R")
		)
	)
	(footprint ""
		(layer "F.Cu")
		(at 407.295096 -102.798372 180)
		(property "Reference" "R376"
			(at 0 0 180)
			(layer "F.SilkS")
			(hide yes)
			(effects
				(font
					(size 1.27 1.27)
				)
			)
		)
		(property "Value" ""
			(at 0 0 180)
			(layer "F.Fab")
			(effects
				(font
					(size 1.27 1.27)
				)
			)
		)
		(duplicate_pad_numbers_are_jumpers no)
		(fp_line
			(start 0.7874 0.4064)
			(end -0.7874 0.4064)
			(stroke
				(width 0.1524)
				(type default)
			)
			(layer "F.SilkS")
		)
		(fp_line
			(start 0.7874 -0.4064)
			(end 0.7874 0.4064)
			(stroke
				(width 0.1524)
				(type default)
			)
			(layer "F.SilkS")
		)
		(fp_line
			(start -0.7874 0.4064)
			(end -0.7874 -0.4064)
			(stroke
				(width 0.1524)
				(type default)
			)
			(layer "F.SilkS")
		)
		(fp_line
			(start -0.7874 -0.4064)
			(end 0.7874 -0.4064)
			(stroke
				(width 0.1524)
				(type default)
			)
			(layer "F.SilkS")
		)
		(fp_line
			(start 0.67945 0.3048)
			(end 0.120396 0.3048)
			(stroke
				(width 0.1)
				(type default)
			)
			(layer "F.Fab")
		)
		(fp_line
			(start 0.67945 -0.3048)
			(end 0.67945 0.3048)
			(stroke
				(width 0.1)
				(type default)
			)
			(layer "F.Fab")
		)
		(fp_line
			(start 0.12065 -0.2794)
			(end 0.12065 -0.3048)
			(stroke
				(width 0.1)
				(type default)
			)
			(layer "F.Fab")
		)
		(fp_line
			(start 0.12065 -0.3048)
			(end 0.67945 -0.3048)
			(stroke
				(width 0.1)
				(type default)
			)
			(layer "F.Fab")
		)
		(fp_line
			(start 0.120396 0.3048)
			(end 0.120396 0.2794)
			(stroke
				(width 0.1)
				(type default)
			)
			(layer "F.Fab")
		)
		(fp_line
			(start 0.120396 0.2794)
			(end -0.12065 0.2794)
			(stroke
				(width 0.1)
				(type default)
			)
			(layer "F.Fab")
		)
		(fp_line
			(start -0.12065 0.3048)
			(end -0.67945 0.3048)
			(stroke
				(width 0.1)
				(type default)
			)
			(layer "F.Fab")
		)
		(fp_line
			(start -0.12065 0.2794)
			(end -0.12065 0.3048)
			(stroke
				(width 0.1)
				(type default)
			)
			(layer "F.Fab")
		)
		(fp_line
			(start -0.12065 -0.2794)
			(end 0.12065 -0.2794)
			(stroke
				(width 0.1)
				(type default)
			)
			(layer "F.Fab")
		)
		(fp_line
			(start -0.12065 -0.305054)
			(end -0.12065 -0.2794)
			(stroke
				(width 0.1)
				(type default)
			)
			(layer "F.Fab")
		)
		(fp_line
			(start -0.67945 0.3048)
			(end -0.67945 -0.305054)
			(stroke
				(width 0.1)
				(type default)
			)
			(layer "F.Fab")
		)
		(fp_line
			(start -0.67945 -0.305054)
			(end -0.12065 -0.305054)
			(stroke
				(width 0.1)
				(type default)
			)
			(layer "F.Fab")
		)
		(pad "1" smd circle
			(at -0.40005 0 180)
			(size 0 0)
			(layers "F.Cu" "F.Mask" "F.Paste")
			(net "NCSI_NIC7_TXD1")
		)
		(pad "2" smd circle
			(at 0.40005 0 180)
			(size 0 0)
			(layers "F.Cu" "F.Mask" "F.Paste")
			(net "GND")
		)
	)
	(footprint ""
		(layer "F.Cu")
		(at 26.930096 -300.406308 -90)
		(property "Reference" "C3017"
			(at 0 0 270)
			(layer "F.SilkS")
			(hide yes)
			(effects
				(font
					(size 1.27 1.27)
				)
			)
		)
		(property "Value" ""
			(at 0 0 270)
			(layer "F.Fab")
			(effects
				(font
					(size 1.27 1.27)
				)
			)
		)
		(duplicate_pad_numbers_are_jumpers no)
		(fp_line
			(start -1.2954 0.5842)
			(end -1.2954 -0.5842)
			(stroke
				(width 0.1524)
				(type default)
			)
			(layer "F.SilkS")
		)
		(fp_line
			(start 1.2954 0.5842)
			(end -1.2954 0.5842)
			(stroke
				(width 0.1524)
				(type default)
			)
			(layer "F.SilkS")
		)
		(fp_line
			(start -1.2954 -0.5842)
			(end 1.2954 -0.5842)
			(stroke
				(width 0.1524)
				(type default)
			)
			(layer "F.SilkS")
		)
		(fp_line
			(start 1.2954 -0.5842)
			(end 1.2954 0.5842)
			(stroke
				(width 0.1524)
				(type default)
			)
			(layer "F.SilkS")
		)
		(fp_line
			(start -0.8636 0.4572)
			(end -0.8636 0.4064)
			(stroke
				(width 0.1)
				(type default)
			)
			(layer "F.Fab")
		)
		(fp_line
			(start 0.8636 0.4572)
			(end -0.8636 0.4572)
			(stroke
				(width 0.1)
				(type default)
			)
			(layer "F.Fab")
		)
		(fp_line
			(start -1.1938 0.4064)
			(end -1.1938 -0.4064)
			(stroke
				(width 0.1)
				(type default)
			)
			(layer "F.Fab")
		)
		(fp_line
			(start -0.8636 0.4064)
			(end -1.1938 0.4064)
			(stroke
				(width 0.1)
				(type default)
			)
			(layer "F.Fab")
		)
		(fp_line
			(start 0.8636 0.4064)
			(end 0.8636 0.4572)
			(stroke
				(width 0.1)
				(type default)
			)
			(layer "F.Fab")
		)
		(fp_line
			(start 1.1938 0.4064)
			(end 0.8636 0.4064)
			(stroke
				(width 0.1)
				(type default)
			)
			(layer "F.Fab")
		)
		(fp_line
			(start -1.1938 -0.4064)
			(end -0.8636 -0.4064)
			(stroke
				(width 0.1)
				(type default)
			)
			(layer "F.Fab")
		)
		(fp_line
			(start -0.8636 -0.4064)
			(end -0.8636 -0.4572)
			(stroke
				(width 0.1)
				(type default)
			)
			(layer "F.Fab")
		)
		(fp_line
			(start 0.8636 -0.4064)
			(end 1.1938 -0.4064)
			(stroke
				(width 0.1)
				(type default)
			)
			(layer "F.Fab")
		)
		(fp_line
			(start 1.1938 -0.4064)
			(end 1.1938 0.4064)
			(stroke
				(width 0.1)
				(type default)
			)
			(layer "F.Fab")
		)
		(fp_line
			(start -0.8636 -0.4572)
			(end 0.8636 -0.4572)
			(stroke
				(width 0.1)
				(type default)
			)
			(layer "F.Fab")
		)
		(fp_line
			(start 0.8636 -0.4572)
			(end 0.8636 -0.4064)
			(stroke
				(width 0.1)
				(type default)
			)
			(layer "F.Fab")
		)
		(pad "1" smd rect
			(at -0.7366 0 180)
			(size 0.7112 0.8128)
			(layers "F.Cu" "F.Mask" "F.Paste")
			(net "P1V8_PLL0_PEX0")
		)
		(pad "2" smd rect
			(at 0.7366 0 180)
			(size 0.7112 0.8128)
			(layers "F.Cu" "F.Mask" "F.Paste")
			(net "GND")
		)
	)
	(footprint ""
		(layer "F.Cu")
		(at 98.446336 -58.323734)
		(property "Reference" "PC391"
			(at 0 0 0)
			(layer "F.SilkS")
			(hide yes)
			(effects
				(font
					(size 1.27 1.27)
				)
			)
		)
		(property "Value" ""
			(at 0 0 0)
			(layer "F.Fab")
			(effects
				(font
					(size 1.27 1.27)
				)
			)
		)
		(duplicate_pad_numbers_are_jumpers no)
		(fp_line
			(start -1.524 -0.762)
			(end 1.524 -0.762)
			(stroke
				(width 0.1524)
				(type default)
			)
			(layer "F.SilkS")
		)
		(fp_line
			(start -1.524 0.762)
			(end -1.524 -0.762)
			(stroke
				(width 0.1524)
				(type default)
			)
			(layer "F.SilkS")
		)
		(fp_line
			(start 1.524 -0.762)
			(end 1.524 0.762)
			(stroke
				(width 0.1524)
				(type default)
			)
			(layer "F.SilkS")
		)
		(fp_line
			(start 1.524 0.762)
			(end -1.524 0.762)
			(stroke
				(width 0.1524)
				(type default)
			)
			(layer "F.SilkS")
		)
		(fp_line
			(start -1.1049 -0.724916)
			(end -1.1049 0.724916)
			(stroke
				(width 0.1)
				(type default)
			)
			(layer "F.Fab")
		)
		(fp_line
			(start -1.1049 0.724916)
			(end 1.1049 0.724916)
			(stroke
				(width 0.1)
				(type default)
			)
			(layer "F.Fab")
		)
		(fp_line
			(start 1.1049 -0.724916)
			(end -1.1049 -0.724916)
			(stroke
				(width 0.1)
				(type default)
			)
			(layer "F.Fab")
		)
		(fp_line
			(start 1.1049 0.724916)
			(end 1.1049 -0.724916)
			(stroke
				(width 0.1)
				(type default)
			)
			(layer "F.Fab")
		)
		(pad "1" smd rect
			(at -0.889 0 180)
			(size 1.016 1.27)
			(layers "F.Cu" "F.Mask" "F.Paste")
			(net "GND")
		)
		(pad "2" smd rect
			(at 0.889 0 180)
			(size 1.016 1.27)
			(layers "F.Cu" "F.Mask" "F.Paste")
			(net "P12V_AUX")
		)
	)
	(footprint ""
		(layer "F.Cu")
		(at 402.140166 -32.848042 90)
		(property "Reference" "PC973"
			(at 0 0 90)
			(layer "F.SilkS")
			(hide yes)
			(effects
				(font
					(size 1.27 1.27)
				)
			)
		)
		(property "Value" ""
			(at 0 0 90)
			(layer "F.Fab")
			(effects
				(font
					(size 1.27 1.27)
				)
			)
		)
		(duplicate_pad_numbers_are_jumpers no)
		(fp_line
			(start 0.7874 -0.4064)
			(end 0.7874 0.4064)
			(stroke
				(width 0.1524)
				(type default)
			)
			(layer "F.SilkS")
		)
		(fp_line
			(start -0.7874 -0.4064)
			(end 0.7874 -0.4064)
			(stroke
				(width 0.1524)
				(type default)
			)
			(layer "F.SilkS")
		)
		(fp_line
			(start 0.7874 0.4064)
			(end -0.7874 0.4064)
			(stroke
				(width 0.1524)
				(type default)
			)
			(layer "F.SilkS")
		)
		(fp_line
			(start -0.7874 0.4064)
			(end -0.7874 -0.4064)
			(stroke
				(width 0.1524)
				(type default)
			)
			(layer "F.SilkS")
		)
		(fp_line
			(start -0.12065 -0.305054)
			(end -0.12065 -0.2794)
			(stroke
				(width 0.1)
				(type default)
			)
			(layer "F.Fab")
		)
		(fp_line
			(start -0.67945 -0.305054)
			(end -0.12065 -0.305054)
			(stroke
				(width 0.1)
				(type default)
			)
			(layer "F.Fab")
		)
		(fp_line
			(start 0.67945 -0.3048)
			(end 0.67945 0.3048)
			(stroke
				(width 0.1)
				(type default)
			)
			(layer "F.Fab")
		)
		(fp_line
			(start 0.12065 -0.3048)
			(end 0.67945 -0.3048)
			(stroke
				(width 0.1)
				(type default)
			)
			(layer "F.Fab")
		)
		(fp_line
			(start 0.12065 -0.2794)
			(end 0.12065 -0.3048)
			(stroke
				(width 0.1)
				(type default)
			)
			(layer "F.Fab")
		)
		(fp_line
			(start -0.12065 -0.2794)
			(end 0.12065 -0.2794)
			(stroke
				(width 0.1)
				(type default)
			)
			(layer "F.Fab")
		)
		(fp_line
			(start 0.120396 0.2794)
			(end -0.12065 0.2794)
			(stroke
				(width 0.1)
				(type default)
			)
			(layer "F.Fab")
		)
		(fp_line
			(start -0.12065 0.2794)
			(end -0.12065 0.3048)
			(stroke
				(width 0.1)
				(type default)
			)
			(layer "F.Fab")
		)
		(fp_line
			(start 0.67945 0.3048)
			(end 0.120396 0.3048)
			(stroke
				(width 0.1)
				(type default)
			)
			(layer "F.Fab")
		)
		(fp_line
			(start 0.120396 0.3048)
			(end 0.120396 0.2794)
			(stroke
				(width 0.1)
				(type default)
			)
			(layer "F.Fab")
		)
		(fp_line
			(start -0.12065 0.3048)
			(end -0.67945 0.3048)
			(stroke
				(width 0.1)
				(type default)
			)
			(layer "F.Fab")
		)
		(fp_line
			(start -0.67945 0.3048)
			(end -0.67945 -0.305054)
			(stroke
				(width 0.1)
				(type default)
			)
			(layer "F.Fab")
		)
		(pad "1" smd circle
			(at -0.40005 0 90)
			(size 0 0)
			(layers "F.Cu" "F.Mask" "F.Paste")
			(net "P3V3_SSD14_CO_DV_DT")
		)
		(pad "2" smd circle
			(at 0.40005 0 90)
			(size 0 0)
			(layers "F.Cu" "F.Mask" "F.Paste")
			(net "GND")
		)
	)
	(footprint ""
		(layer "F.Cu")
		(at 320.488056 -100.459032 90)
		(property "Reference" "R744"
			(at 0 0 90)
			(layer "F.SilkS")
			(hide yes)
			(effects
				(font
					(size 1.27 1.27)
				)
			)
		)
		(property "Value" ""
			(at 0 0 90)
			(layer "F.Fab")
			(effects
				(font
					(size 1.27 1.27)
				)
			)
		)
		(duplicate_pad_numbers_are_jumpers no)
		(fp_line
			(start 0.7874 -0.4064)
			(end 0.7874 0.4064)
			(stroke
				(width 0.1524)
				(type default)
			)
			(layer "F.SilkS")
		)
		(fp_line
			(start -0.7874 -0.4064)
			(end 0.7874 -0.4064)
			(stroke
				(width 0.1524)
				(type default)
			)
			(layer "F.SilkS")
		)
		(fp_line
			(start 0.7874 0.4064)
			(end -0.7874 0.4064)
			(stroke
				(width 0.1524)
				(type default)
			)
			(layer "F.SilkS")
		)
		(fp_line
			(start -0.7874 0.4064)
			(end -0.7874 -0.4064)
			(stroke
				(width 0.1524)
				(type default)
			)
			(layer "F.SilkS")
		)
		(fp_line
			(start -0.12065 -0.305054)
			(end -0.12065 -0.2794)
			(stroke
				(width 0.1)
				(type default)
			)
			(layer "F.Fab")
		)
		(fp_line
			(start -0.67945 -0.305054)
			(end -0.12065 -0.305054)
			(stroke
				(width 0.1)
				(type default)
			)
			(layer "F.Fab")
		)
		(fp_line
			(start 0.67945 -0.3048)
			(end 0.67945 0.3048)
			(stroke
				(width 0.1)
				(type default)
			)
			(layer "F.Fab")
		)
		(fp_line
			(start 0.12065 -0.3048)
			(end 0.67945 -0.3048)
			(stroke
				(width 0.1)
				(type default)
			)
			(layer "F.Fab")
		)
		(fp_line
			(start 0.12065 -0.2794)
			(end 0.12065 -0.3048)
			(stroke
				(width 0.1)
				(type default)
			)
			(layer "F.Fab")
		)
		(fp_line
			(start -0.12065 -0.2794)
			(end 0.12065 -0.2794)
			(stroke
				(width 0.1)
				(type default)
			)
			(layer "F.Fab")
		)
		(fp_line
			(start 0.120396 0.2794)
			(end -0.12065 0.2794)
			(stroke
				(width 0.1)
				(type default)
			)
			(layer "F.Fab")
		)
		(fp_line
			(start -0.12065 0.2794)
			(end -0.12065 0.3048)
			(stroke
				(width 0.1)
				(type default)
			)
			(layer "F.Fab")
		)
		(fp_line
			(start 0.67945 0.3048)
			(end 0.120396 0.3048)
			(stroke
				(width 0.1)
				(type default)
			)
			(layer "F.Fab")
		)
		(fp_line
			(start 0.120396 0.3048)
			(end 0.120396 0.2794)
			(stroke
				(width 0.1)
				(type default)
			)
			(layer "F.Fab")
		)
		(fp_line
			(start -0.12065 0.3048)
			(end -0.67945 0.3048)
			(stroke
				(width 0.1)
				(type default)
			)
			(layer "F.Fab")
		)
		(fp_line
			(start -0.67945 0.3048)
			(end -0.67945 -0.305054)
			(stroke
				(width 0.1)
				(type default)
			)
			(layer "F.Fab")
		)
		(pad "1" smd circle
			(at -0.40005 0 90)
			(size 0 0)
			(layers "F.Cu" "F.Mask" "F.Paste")
			(net "P12V_NIC5_R")
		)
		(pad "2" smd circle
			(at 0.40005 0 90)
			(size 0 0)
			(layers "F.Cu" "F.Mask" "F.Paste")
			(net "P12V_NIC5_VIN_P")
		)
	)
)
